# BASEBOARD_FAB2 (Tioga Pass) — schematic netlist excerpt (pin names and nets, part order shuffled) for the footprints in the layout excerpt that follows; sources: Cadence DE-HDL packaged netlist, KiCad conversion of Wiwynn_Tioga_Pass_MB.brd

R4G6  RES  120.0 1% CHIP  pkg 0603  page 233 : A = PVPP_GHJ ; B = GND
C30W8  SC22U16V5MX-4-GP  20%  pkg SMD-BCG5  page 253 : \1\ = P5V_STBY_USBC ; \2\ = GND
R1T26  RES  8.2K 1% CHIP  pkg 0402  page 146 : A = A_USB2AVRES ; B = GND

(kicad_pcb
	(version 20260206)
	(generator "pcbnew")
	(generator_version "10.0")
	(general
		(thickness 1.6)
		(legacy_teardrops no)
	)
	(paper "A4")
	(title_block
		(title "Wiwynn_Tioga_Pass_MB.brd")
		(comment 1 "Tioga Pass / footprints 2333-2335 of 4770")
	)
	(layers
		(0 "F.Cu" signal "TOP")
		(4 "In1.Cu" signal "L2GND")
		(6 "In2.Cu" signal "L3")
		(8 "In3.Cu" signal "L4GND")
		(10 "In4.Cu" signal "L5")
		(12 "In5.Cu" signal "L6GND")
		(14 "In6.Cu" signal "L7VCC")
		(16 "In7.Cu" signal "L8VCC")
		(18 "In8.Cu" signal "L9GND")
		(20 "In9.Cu" signal "L10")
		(22 "In10.Cu" signal "L11GND")
		(24 "In11.Cu" signal "L12")
		(26 "In12.Cu" signal "L13GND")
		(2 "B.Cu" signal "BOTTOM")
		(9 "F.Adhes" user "F.Adhesive")
		(11 "B.Adhes" user "B.Adhesive")
		(13 "F.Paste" user "Package Geometry/Pastemask Top")
		(15 "B.Paste" user "Package Geometry/Pastemask Bottom")
		(5 "F.SilkS" user "Ref Des/Silkscreen Top")
		(7 "B.SilkS" user "Ref Des/Silkscreen Bottom")
		(1 "F.Mask" user "Board Geometry/Soldermask Top")
		(3 "B.Mask" user "Board Geometry/Soldermask Bottom")
		(17 "Dwgs.User" user "User.Drawings")
		(19 "Cmts.User" user "User.Comments")
		(21 "Eco1.User" user "User.Eco1")
		(23 "Eco2.User" user "User.Eco2")
		(25 "Edge.Cuts" user "Board Geometry/Outline")
		(27 "Margin" user)
		(31 "F.CrtYd" user "Package Geometry/Place Bound Top")
		(29 "B.CrtYd" user "Package Geometry/Place Bound Bottom")
		(35 "F.Fab" user "Ref Des/Assembly Top")
		(33 "B.Fab" user "Ref Des/Assembly Bottom")
	)
	(footprint ""
		(layer "F.Cu")
		(at 166.271448 -10.0711 90)
		(property "Reference" "R4G6"
			(at 0 0 90)
			(layer "F.SilkS")
			(hide yes)
			(effects
				(font
					(size 1.27 1.27)
				)
			)
		)
		(property "Value" ""
			(at 0 0 90)
			(layer "F.Fab")
			(effects
				(font
					(size 1.27 1.27)
				)
			)
		)
		(duplicate_pad_numbers_are_jumpers no)
		(fp_poly
			(pts
				(xy -0.4953 -0.2032) (xy 0.4953 -0.2032) (xy 0.4953 1.6002) (xy -0.4953 1.6002)
			)
			(stroke
				(width 0)
				(type default)
			)
			(fill no)
			(layer "F.CrtYd")
		)
		(fp_line
			(start 0.4953 -0.2032)
			(end 0.4953 1.6002)
			(stroke
				(width 0.1)
				(type default)
			)
			(layer "F.Fab")
		)
		(fp_line
			(start -0.4953 -0.2032)
			(end 0.4953 -0.2032)
			(stroke
				(width 0.1)
				(type default)
			)
			(layer "F.Fab")
		)
		(fp_line
			(start 0.4953 1.6002)
			(end -0.4953 1.6002)
			(stroke
				(width 0.1)
				(type default)
			)
			(layer "F.Fab")
		)
		(fp_line
			(start -0.4953 1.6002)
			(end -0.4953 -0.2032)
			(stroke
				(width 0.1)
				(type default)
			)
			(layer "F.Fab")
		)
		(pad "1" smd rect
			(at 0 0 90)
			(size 0.762 0.889)
			(layers "F.Cu" "F.Mask" "F.Paste")
			(net "PVPP_GHJ")
		)
		(pad "2" smd rect
			(at 0 1.397 90)
			(size 0.762 0.889)
			(layers "F.Cu" "F.Mask" "F.Paste")
			(net "GND")
		)
		(zone
			(layer "F.Cu")
			(hatch none 0.5)
			(connect_pads
				(clearance 0)
			)
			(min_thickness 0.25)
			(keepout
				(tracks allowed)
				(vias not_allowed)
				(pads allowed)
				(copperpour not_allowed)
				(footprints allowed)
			)
			(placement
				(enabled no)
				(sheetname "")
			)
			(fill
				(thermal_gap 0.5)
				(thermal_bridge_width 0.5)
				(island_removal_mode 0)
			)
			(polygon
				(pts
					(xy 167.223948 -10.4521) (xy 166.715948 -10.4521) (xy 166.715948 -9.6901) (xy 167.223948 -9.6901)
				)
			)
		)
		(zone
			(layer "F.Cu")
			(hatch none 0.5)
			(connect_pads
				(clearance 0)
			)
			(min_thickness 0.25)
			(keepout
				(tracks not_allowed)
				(vias allowed)
				(pads allowed)
				(copperpour not_allowed)
				(footprints allowed)
			)
			(placement
				(enabled no)
				(sheetname "")
			)
			(fill
				(thermal_gap 0.5)
				(thermal_bridge_width 0.5)
				(island_removal_mode 0)
			)
			(polygon
				(pts
					(xy 167.223948 -9.6901) (xy 167.223948 -10.4521) (xy 166.715948 -10.4521) (xy 166.715948 -9.6901)
				)
			)
		)
	)
	(footprint ""
		(layer "B.Cu")
		(at 488.244896 -55.856378)
		(property "Reference" "C30W8"
			(at 0 0 0)
			(layer "B.SilkS")
			(hide yes)
			(effects
				(font
					(size 1.27 1.27)
				)
				(justify mirror)
			)
		)
		(property "Value" "*"
			(at 0.0762 -6.2357 0)
			(unlocked yes)
			(layer "B.Fab")
			(hide yes)
			(effects
				(font
					(size 1.27 1.016)
					(thickness 0.1524)
				)
				(justify mirror)
			)
		)
		(property "Device Type" "SC22U16V5MX-4-GP_SMD-BCG5-SC22A"
			(at 0.0762 -8.2677 0)
			(unlocked yes)
			(layer "B.Fab")
			(hide yes)
			(effects
				(font
					(size 1.27 1.016)
					(thickness 0.1524)
				)
				(justify mirror)
			)
		)
		(duplicate_pad_numbers_are_jumpers no)
		(fp_line
			(start -0.635 0)
			(end 0.635 0)
			(stroke
				(width 0.508)
				(type default)
			)
			(layer "B.SilkS")
		)
		(fp_rect
			(start 0.9652 1.778)
			(end -0.9652 -1.778)
			(stroke
				(width 0)
				(type default)
			)
			(fill no)
			(layer "B.CrtYd")
		)
		(fp_poly
			(pts
				(xy 0.9652 -1.778) (xy -0.9652 -1.778) (xy -0.9652 1.778) (xy 0.9652 1.778)
			)
			(stroke
				(width 0)
				(type default)
			)
			(fill no)
			(layer "B.Fab")
		)
		(pad "1" smd rect
			(at 0 -0.9652 180)
			(size 1.397 1.143)
			(layers "B.Cu" "B.Mask" "B.Paste")
			(net "P5V_STBY_USBC")
		)
		(pad "2" smd rect
			(at 0 0.9652 180)
			(size 1.397 1.143)
			(layers "B.Cu" "B.Mask" "B.Paste")
			(net "GND")
		)
	)
	(footprint ""
		(layer "B.Cu")
		(at 406.892506 -32.6644 -90)
		(property "Reference" "R1T26"
			(at 0 0 90)
			(layer "B.SilkS")
			(hide yes)
			(effects
				(font
					(size 1.27 1.27)
				)
				(justify mirror)
			)
		)
		(property "Value" ""
			(at 0 0 90)
			(layer "B.Fab")
			(effects
				(font
					(size 1.27 1.27)
				)
				(justify mirror)
			)
		)
		(duplicate_pad_numbers_are_jumpers no)
		(fp_poly
			(pts
				(xy 0.2794 -0.1016) (xy -0.2794 -0.1016) (xy -0.2794 0.9906) (xy 0.2794 0.9906)
			)
			(stroke
				(width 0)
				(type default)
			)
			(fill no)
			(layer "B.CrtYd")
		)
		(fp_line
			(start -0.2794 0.9906)
			(end -0.2794 -0.1016)
			(stroke
				(width 0.1)
				(type default)
			)
			(layer "B.Fab")
		)
		(fp_line
			(start 0.2794 0.9906)
			(end -0.2794 0.9906)
			(stroke
				(width 0.1)
				(type default)
			)
			(layer "B.Fab")
		)
		(fp_line
			(start -0.2794 -0.1016)
			(end 0.2794 -0.1016)
			(stroke
				(width 0.1)
				(type default)
			)
			(layer "B.Fab")
		)
		(fp_line
			(start 0.2794 -0.1016)
			(end 0.2794 0.9906)
			(stroke
				(width 0.1)
				(type default)
			)
			(layer "B.Fab")
		)
		(pad "1" smd rect
			(at 0 0 90)
			(size 0.508 0.508)
			(layers "B.Cu" "B.Mask" "B.Paste")
			(net "A_USB2AVRES")
		)
		(pad "2" smd rect
			(at 0 0.889 90)
			(size 0.508 0.508)
			(layers "B.Cu" "B.Mask" "B.Paste")
			(net "GND")
		)
		(zone
			(layer "B.Cu")
			(hatch none 0.5)
			(connect_pads
				(clearance 0)
			)
			(min_thickness 0.25)
			(keepout
				(tracks not_allowed)
				(vias allowed)
				(pads allowed)
				(copperpour not_allowed)
				(footprints allowed)
			)
			(placement
				(enabled no)
				(sheetname "")
			)
			(fill
				(thermal_gap 0.5)
				(thermal_bridge_width 0.5)
				(island_removal_mode 0)
			)
			(polygon
				(pts
					(xy 406.257506 -32.4104) (xy 406.257506 -32.9184) (xy 406.638506 -32.9184) (xy 406.638506 -32.4104)
				)
			)
		)
		(zone
			(layer "B.Cu")
			(hatch none 0.5)
			(connect_pads
				(clearance 0)
			)
			(min_thickness 0.25)
			(keepout
				(tracks allowed)
				(vias not_allowed)
				(pads allowed)
				(copperpour not_allowed)
				(footprints allowed)
			)
			(placement
				(enabled no)
				(sheetname "")
			)
			(fill
				(thermal_gap 0.5)
				(thermal_bridge_width 0.5)
				(island_removal_mode 0)
			)
			(polygon
				(pts
					(xy 406.638506 -32.4104) (xy 406.638506 -32.9184) (xy 406.257506 -32.9184) (xy 406.257506 -32.4104)
				)
			)
		)
	)
)
